(kicad_pcb
	(version 20260206)
	(generator "pcbnew")
	(generator_version "10.0")
	(general
		(thickness 1.6)
		(legacy_teardrops no)
	)
	(paper "A4")
	(title_block
		(title "04192023_DAF0TMB3IC0_F0TG_MB_C_brd_V02_OCP.brd")
		(comment 1 "Grand Teton / footprints 8097-8104 of 8354")
	)
	(layers
		(0 "F.Cu" signal "TOP")
		(4 "In1.Cu" signal "GND")
		(6 "In2.Cu" signal "IN1")
		(8 "In3.Cu" signal "GND1")
		(10 "In4.Cu" signal "IN2")
		(12 "In5.Cu" signal "GND2")
		(14 "In6.Cu" signal "IN3")
		(16 "In7.Cu" signal "GND3")
		(18 "In8.Cu" signal "VCC")
		(20 "In9.Cu" signal "VCC1")
		(22 "In10.Cu" signal "GND4")
		(24 "In11.Cu" signal "IN4")
		(26 "In12.Cu" signal "GND5")
		(28 "In13.Cu" signal "IN5")
		(30 "In14.Cu" signal "GND6")
		(32 "In15.Cu" signal "IN6")
		(34 "In16.Cu" signal "GND7")
		(2 "B.Cu" signal "BOTTOM")
		(9 "F.Adhes" user "F.Adhesive")
		(11 "B.Adhes" user "B.Adhesive")
		(13 "F.Paste" user "Package Geometry/Pastemask Top")
		(15 "B.Paste" user "Package Geometry/Pastemask Bottom")
		(5 "F.SilkS" user "Ref Des/Silkscreen Top")
		(7 "B.SilkS" user "Ref Des/Silkscreen Bottom")
		(1 "F.Mask" user "Board Geometry/Soldermask Top")
		(3 "B.Mask" user "Board Geometry/Soldermask Bottom")
		(17 "Dwgs.User" user "User.Drawings")
		(19 "Cmts.User" user "User.Comments")
		(21 "Eco1.User" user "User.Eco1")
		(23 "Eco2.User" user "User.Eco2")
		(25 "Edge.Cuts" user "Board Geometry/Outline")
		(27 "Margin" user)
		(31 "F.CrtYd" user "Package Geometry/Place Bound Top")
		(29 "B.CrtYd" user "Package Geometry/Place Bound Bottom")
		(35 "F.Fab" user "Ref Des/Assembly Top")
		(33 "B.Fab" user "Ref Des/Assembly Bottom")
	)
	(footprint ""
		(layer "B.Cu")
		(at 129.305304 -34.670492)
		(property "Reference" "C6081"
			(at 0 0 0)
			(layer "B.SilkS")
			(hide yes)
			(effects
				(font
					(size 1.27 1.27)
				)
				(justify mirror)
			)
		)
		(property "Value" ""
			(at 0 0 0)
			(layer "B.Fab")
			(effects
				(font
					(size 1.27 1.27)
				)
				(justify mirror)
			)
		)
		(duplicate_pad_numbers_are_jumpers no)
		(fp_line
			(start -0.7874 -0.4064)
			(end -0.7874 0.4064)
			(stroke
				(width 0.1524)
				(type default)
			)
			(layer "B.SilkS")
		)
		(fp_line
			(start -0.7874 0.4064)
			(end 0.7874 0.4064)
			(stroke
				(width 0.1524)
				(type default)
			)
			(layer "B.SilkS")
		)
		(fp_line
			(start 0.7874 -0.4064)
			(end -0.7874 -0.4064)
			(stroke
				(width 0.1524)
				(type default)
			)
			(layer "B.SilkS")
		)
		(fp_line
			(start 0.7874 0.4064)
			(end 0.7874 -0.4064)
			(stroke
				(width 0.1524)
				(type default)
			)
			(layer "B.SilkS")
		)
		(fp_line
			(start -0.67945 -0.3048)
			(end -0.67945 0.3048)
			(stroke
				(width 0.1)
				(type default)
			)
			(layer "B.Fab")
		)
		(fp_line
			(start -0.67945 0.3048)
			(end -0.120396 0.3048)
			(stroke
				(width 0.1)
				(type default)
			)
			(layer "B.Fab")
		)
		(fp_line
			(start -0.12065 -0.3048)
			(end -0.67945 -0.3048)
			(stroke
				(width 0.1)
				(type default)
			)
			(layer "B.Fab")
		)
		(fp_line
			(start -0.12065 -0.2794)
			(end -0.12065 -0.3048)
			(stroke
				(width 0.1)
				(type default)
			)
			(layer "B.Fab")
		)
		(fp_line
			(start -0.120396 0.2794)
			(end 0.12065 0.2794)
			(stroke
				(width 0.1)
				(type default)
			)
			(layer "B.Fab")
		)
		(fp_line
			(start -0.120396 0.3048)
			(end -0.120396 0.2794)
			(stroke
				(width 0.1)
				(type default)
			)
			(layer "B.Fab")
		)
		(fp_line
			(start 0.12065 -0.305054)
			(end 0.12065 -0.2794)
			(stroke
				(width 0.1)
				(type default)
			)
			(layer "B.Fab")
		)
		(fp_line
			(start 0.12065 -0.2794)
			(end -0.12065 -0.2794)
			(stroke
				(width 0.1)
				(type default)
			)
			(layer "B.Fab")
		)
		(fp_line
			(start 0.12065 0.2794)
			(end 0.12065 0.3048)
			(stroke
				(width 0.1)
				(type default)
			)
			(layer "B.Fab")
		)
		(fp_line
			(start 0.12065 0.3048)
			(end 0.67945 0.3048)
			(stroke
				(width 0.1)
				(type default)
			)
			(layer "B.Fab")
		)
		(fp_line
			(start 0.67945 -0.305054)
			(end 0.12065 -0.305054)
			(stroke
				(width 0.1)
				(type default)
			)
			(layer "B.Fab")
		)
		(fp_line
			(start 0.67945 0.3048)
			(end 0.67945 -0.305054)
			(stroke
				(width 0.1)
				(type default)
			)
			(layer "B.Fab")
		)
		(pad "1" smd circle
			(at 0.40005 0 180)
			(size 0 0)
			(layers "B.Cu" "B.Mask" "B.Paste")
			(net "P1V2_AUX")
		)
		(pad "2" smd circle
			(at -0.40005 0 180)
			(size 0 0)
			(layers "B.Cu" "B.Mask" "B.Paste")
			(net "GND")
		)
	)
	(footprint ""
		(layer "B.Cu")
		(at 311.91835 -396.393162 -90)
		(property "Reference" "C514"
			(at 0 0 90)
			(layer "B.SilkS")
			(hide yes)
			(effects
				(font
					(size 1.27 1.27)
				)
				(justify mirror)
			)
		)
		(property "Value" ""
			(at 0 0 90)
			(layer "B.Fab")
			(effects
				(font
					(size 1.27 1.27)
				)
				(justify mirror)
			)
		)
		(duplicate_pad_numbers_are_jumpers no)
		(fp_line
			(start -0.299974 0.150114)
			(end 0.299974 0.150114)
			(stroke
				(width 0.1)
				(type default)
			)
			(layer "B.Fab")
		)
		(fp_line
			(start 0.299974 0.150114)
			(end 0.299974 -0.150114)
			(stroke
				(width 0.1)
				(type default)
			)
			(layer "B.Fab")
		)
		(fp_line
			(start -0.299974 -0.150114)
			(end -0.299974 0.150114)
			(stroke
				(width 0.1)
				(type default)
			)
			(layer "B.Fab")
		)
		(fp_line
			(start 0.299974 -0.150114)
			(end -0.299974 -0.150114)
			(stroke
				(width 0.1)
				(type default)
			)
			(layer "B.Fab")
		)
		(pad "1" smd rect
			(at 0.2667 0 90)
			(size 0.3048 0.381)
			(layers "B.Cu" "B.Mask" "B.Paste")
			(net "P1V8_CPU0_RT0_1A")
		)
		(pad "2" smd rect
			(at -0.2667 0 90)
			(size 0.3048 0.381)
			(layers "B.Cu" "B.Mask" "B.Paste")
			(net "GND")
		)
	)
	(footprint ""
		(layer "B.Cu")
		(at 45.418502 -387.05028)
		(property "Reference" "C257"
			(at 0 0 0)
			(layer "B.SilkS")
			(hide yes)
			(effects
				(font
					(size 1.27 1.27)
				)
				(justify mirror)
			)
		)
		(property "Value" ""
			(at 0 0 0)
			(layer "B.Fab")
			(effects
				(font
					(size 1.27 1.27)
				)
				(justify mirror)
			)
		)
		(duplicate_pad_numbers_are_jumpers no)
		(fp_line
			(start -0.299974 -0.150114)
			(end -0.299974 0.150114)
			(stroke
				(width 0.1)
				(type default)
			)
			(layer "B.Fab")
		)
		(fp_line
			(start -0.299974 0.150114)
			(end 0.299974 0.150114)
			(stroke
				(width 0.1)
				(type default)
			)
			(layer "B.Fab")
		)
		(fp_line
			(start 0.299974 -0.150114)
			(end -0.299974 -0.150114)
			(stroke
				(width 0.1)
				(type default)
			)
			(layer "B.Fab")
		)
		(fp_line
			(start 0.299974 0.150114)
			(end 0.299974 -0.150114)
			(stroke
				(width 0.1)
				(type default)
			)
			(layer "B.Fab")
		)
		(pad "1" smd rect
			(at 0.2667 0 180)
			(size 0.3048 0.381)
			(layers "B.Cu" "B.Mask" "B.Paste")
			(net "P0V9_CPU1_RT0_2A")
		)
		(pad "2" smd rect
			(at -0.2667 0 180)
			(size 0.3048 0.381)
			(layers "B.Cu" "B.Mask" "B.Paste")
			(net "GND")
		)
	)
	(footprint ""
		(layer "B.Cu")
		(at 167.377618 -417.962588)
		(property "Reference" "R4128"
			(at 0 0 0)
			(layer "B.SilkS")
			(hide yes)
			(effects
				(font
					(size 1.27 1.27)
				)
				(justify mirror)
			)
		)
		(property "Value" ""
			(at 0 0 0)
			(layer "B.Fab")
			(effects
				(font
					(size 1.27 1.27)
				)
				(justify mirror)
			)
		)
		(duplicate_pad_numbers_are_jumpers no)
		(fp_line
			(start -0.7874 -0.4064)
			(end -0.7874 0.4064)
			(stroke
				(width 0.1524)
				(type default)
			)
			(layer "B.SilkS")
		)
		(fp_line
			(start -0.7874 0.4064)
			(end 0.7874 0.4064)
			(stroke
				(width 0.1524)
				(type default)
			)
			(layer "B.SilkS")
		)
		(fp_line
			(start 0.7874 -0.4064)
			(end -0.7874 -0.4064)
			(stroke
				(width 0.1524)
				(type default)
			)
			(layer "B.SilkS")
		)
		(fp_line
			(start 0.7874 0.4064)
			(end 0.7874 -0.4064)
			(stroke
				(width 0.1524)
				(type default)
			)
			(layer "B.SilkS")
		)
		(fp_line
			(start -0.67945 -0.3048)
			(end -0.67945 0.3048)
			(stroke
				(width 0.1)
				(type default)
			)
			(layer "B.Fab")
		)
		(fp_line
			(start -0.67945 0.3048)
			(end -0.120396 0.3048)
			(stroke
				(width 0.1)
				(type default)
			)
			(layer "B.Fab")
		)
		(fp_line
			(start -0.12065 -0.3048)
			(end -0.67945 -0.3048)
			(stroke
				(width 0.1)
				(type default)
			)
			(layer "B.Fab")
		)
		(fp_line
			(start -0.12065 -0.2794)
			(end -0.12065 -0.3048)
			(stroke
				(width 0.1)
				(type default)
			)
			(layer "B.Fab")
		)
		(fp_line
			(start -0.120396 0.2794)
			(end 0.12065 0.2794)
			(stroke
				(width 0.1)
				(type default)
			)
			(layer "B.Fab")
		)
		(fp_line
			(start -0.120396 0.3048)
			(end -0.120396 0.2794)
			(stroke
				(width 0.1)
				(type default)
			)
			(layer "B.Fab")
		)
		(fp_line
			(start 0.12065 -0.305054)
			(end 0.12065 -0.2794)
			(stroke
				(width 0.1)
				(type default)
			)
			(layer "B.Fab")
		)
		(fp_line
			(start 0.12065 -0.2794)
			(end -0.12065 -0.2794)
			(stroke
				(width 0.1)
				(type default)
			)
			(layer "B.Fab")
		)
		(fp_line
			(start 0.12065 0.2794)
			(end 0.12065 0.3048)
			(stroke
				(width 0.1)
				(type default)
			)
			(layer "B.Fab")
		)
		(fp_line
			(start 0.12065 0.3048)
			(end 0.67945 0.3048)
			(stroke
				(width 0.1)
				(type default)
			)
			(layer "B.Fab")
		)
		(fp_line
			(start 0.67945 -0.305054)
			(end 0.12065 -0.305054)
			(stroke
				(width 0.1)
				(type default)
			)
			(layer "B.Fab")
		)
		(fp_line
			(start 0.67945 0.3048)
			(end 0.67945 -0.305054)
			(stroke
				(width 0.1)
				(type default)
			)
			(layer "B.Fab")
		)
		(pad "1" smd circle
			(at 0.40005 0 180)
			(size 0 0)
			(layers "B.Cu" "B.Mask" "B.Paste")
			(net "P3V3_AUX")
		)
		(pad "2" smd circle
			(at -0.40005 0 180)
			(size 0 0)
			(layers "B.Cu" "B.Mask" "B.Paste")
			(net "GPU_3V3IO_RSVD0_FFU_ISO")
		)
	)
	(footprint ""
		(layer "B.Cu")
		(at 184.681114 -417.575238 180)
		(property "Reference" "R2811"
			(at 0 0 0)
			(layer "B.SilkS")
			(hide yes)
			(effects
				(font
					(size 1.27 1.27)
				)
				(justify mirror)
			)
		)
		(property "Value" ""
			(at 0 0 0)
			(layer "B.Fab")
			(effects
				(font
					(size 1.27 1.27)
				)
				(justify mirror)
			)
		)
		(duplicate_pad_numbers_are_jumpers no)
		(fp_line
			(start 0.7874 0.4064)
			(end 0.7874 -0.4064)
			(stroke
				(width 0.1524)
				(type default)
			)
			(layer "B.SilkS")
		)
		(fp_line
			(start 0.7874 -0.4064)
			(end -0.7874 -0.4064)
			(stroke
				(width 0.1524)
				(type default)
			)
			(layer "B.SilkS")
		)
		(fp_line
			(start -0.7874 0.4064)
			(end 0.7874 0.4064)
			(stroke
				(width 0.1524)
				(type default)
			)
			(layer "B.SilkS")
		)
		(fp_line
			(start -0.7874 -0.4064)
			(end -0.7874 0.4064)
			(stroke
				(width 0.1524)
				(type default)
			)
			(layer "B.SilkS")
		)
		(fp_line
			(start 0.67945 0.3048)
			(end 0.67945 -0.305054)
			(stroke
				(width 0.1)
				(type default)
			)
			(layer "B.Fab")
		)
		(fp_line
			(start 0.67945 -0.305054)
			(end 0.12065 -0.305054)
			(stroke
				(width 0.1)
				(type default)
			)
			(layer "B.Fab")
		)
		(fp_line
			(start 0.12065 0.3048)
			(end 0.67945 0.3048)
			(stroke
				(width 0.1)
				(type default)
			)
			(layer "B.Fab")
		)
		(fp_line
			(start 0.12065 0.2794)
			(end 0.12065 0.3048)
			(stroke
				(width 0.1)
				(type default)
			)
			(layer "B.Fab")
		)
		(fp_line
			(start 0.12065 -0.2794)
			(end -0.12065 -0.2794)
			(stroke
				(width 0.1)
				(type default)
			)
			(layer "B.Fab")
		)
		(fp_line
			(start 0.12065 -0.305054)
			(end 0.12065 -0.2794)
			(stroke
				(width 0.1)
				(type default)
			)
			(layer "B.Fab")
		)
		(fp_line
			(start -0.120396 0.3048)
			(end -0.120396 0.2794)
			(stroke
				(width 0.1)
				(type default)
			)
			(layer "B.Fab")
		)
		(fp_line
			(start -0.120396 0.2794)
			(end 0.12065 0.2794)
			(stroke
				(width 0.1)
				(type default)
			)
			(layer "B.Fab")
		)
		(fp_line
			(start -0.12065 -0.2794)
			(end -0.12065 -0.3048)
			(stroke
				(width 0.1)
				(type default)
			)
			(layer "B.Fab")
		)
		(fp_line
			(start -0.12065 -0.3048)
			(end -0.67945 -0.3048)
			(stroke
				(width 0.1)
				(type default)
			)
			(layer "B.Fab")
		)
		(fp_line
			(start -0.67945 0.3048)
			(end -0.120396 0.3048)
			(stroke
				(width 0.1)
				(type default)
			)
			(layer "B.Fab")
		)
		(fp_line
			(start -0.67945 -0.3048)
			(end -0.67945 0.3048)
			(stroke
				(width 0.1)
				(type default)
			)
			(layer "B.Fab")
		)
		(pad "1" smd circle
			(at 0.40005 0)
			(size 0 0)
			(layers "B.Cu" "B.Mask" "B.Paste")
			(net "SMB_FAN_3V3AUX_BUF_SCL")
		)
		(pad "2" smd circle
			(at -0.40005 0)
			(size 0 0)
			(layers "B.Cu" "B.Mask" "B.Paste")
			(net "SMB_FAN_3V3AUX_BUF_R_SCL")
		)
	)
	(footprint ""
		(layer "B.Cu")
		(at 99.94519 -387.768592 180)
		(property "Reference" "C349"
			(at 0 0 0)
			(layer "B.SilkS")
			(hide yes)
			(effects
				(font
					(size 1.27 1.27)
				)
				(justify mirror)
			)
		)
		(property "Value" ""
			(at 0 0 0)
			(layer "B.Fab")
			(effects
				(font
					(size 1.27 1.27)
				)
				(justify mirror)
			)
		)
		(duplicate_pad_numbers_are_jumpers no)
		(fp_line
			(start 0.299974 0.150114)
			(end 0.299974 -0.150114)
			(stroke
				(width 0.1)
				(type default)
			)
			(layer "B.Fab")
		)
		(fp_line
			(start 0.299974 -0.150114)
			(end -0.299974 -0.150114)
			(stroke
				(width 0.1)
				(type default)
			)
			(layer "B.Fab")
		)
		(fp_line
			(start -0.299974 0.150114)
			(end 0.299974 0.150114)
			(stroke
				(width 0.1)
				(type default)
			)
			(layer "B.Fab")
		)
		(fp_line
			(start -0.299974 -0.150114)
			(end -0.299974 0.150114)
			(stroke
				(width 0.1)
				(type default)
			)
			(layer "B.Fab")
		)
		(pad "1" smd rect
			(at 0.2667 0)
			(size 0.3048 0.381)
			(layers "B.Cu" "B.Mask" "B.Paste")
			(net "P0V9_CPU1_RT1_2A")
		)
		(pad "2" smd rect
			(at -0.2667 0)
			(size 0.3048 0.381)
			(layers "B.Cu" "B.Mask" "B.Paste")
			(net "GND")
		)
	)
	(footprint ""
		(layer "B.Cu")
		(at 415.712402 -195.85051 180)
		(property "Reference" "R1680"
			(at 0 0 0)
			(layer "B.SilkS")
			(hide yes)
			(effects
				(font
					(size 1.27 1.27)
				)
				(justify mirror)
			)
		)
		(property "Value" ""
			(at 0 0 0)
			(layer "B.Fab")
			(effects
				(font
					(size 1.27 1.27)
				)
				(justify mirror)
			)
		)
		(duplicate_pad_numbers_are_jumpers no)
		(fp_line
			(start 0.7874 0.4064)
			(end 0.7874 -0.4064)
			(stroke
				(width 0.1524)
				(type default)
			)
			(layer "B.SilkS")
		)
		(fp_line
			(start 0.7874 -0.4064)
			(end -0.7874 -0.4064)
			(stroke
				(width 0.1524)
				(type default)
			)
			(layer "B.SilkS")
		)
		(fp_line
			(start -0.7874 0.4064)
			(end 0.7874 0.4064)
			(stroke
				(width 0.1524)
				(type default)
			)
			(layer "B.SilkS")
		)
		(fp_line
			(start -0.7874 -0.4064)
			(end -0.7874 0.4064)
			(stroke
				(width 0.1524)
				(type default)
			)
			(layer "B.SilkS")
		)
		(fp_line
			(start 0.67945 0.3048)
			(end 0.67945 -0.305054)
			(stroke
				(width 0.1)
				(type default)
			)
			(layer "B.Fab")
		)
		(fp_line
			(start 0.67945 -0.305054)
			(end 0.12065 -0.305054)
			(stroke
				(width 0.1)
				(type default)
			)
			(layer "B.Fab")
		)
		(fp_line
			(start 0.12065 0.3048)
			(end 0.67945 0.3048)
			(stroke
				(width 0.1)
				(type default)
			)
			(layer "B.Fab")
		)
		(fp_line
			(start 0.12065 0.2794)
			(end 0.12065 0.3048)
			(stroke
				(width 0.1)
				(type default)
			)
			(layer "B.Fab")
		)
		(fp_line
			(start 0.12065 -0.2794)
			(end -0.12065 -0.2794)
			(stroke
				(width 0.1)
				(type default)
			)
			(layer "B.Fab")
		)
		(fp_line
			(start 0.12065 -0.305054)
			(end 0.12065 -0.2794)
			(stroke
				(width 0.1)
				(type default)
			)
			(layer "B.Fab")
		)
		(fp_line
			(start -0.120396 0.3048)
			(end -0.120396 0.2794)
			(stroke
				(width 0.1)
				(type default)
			)
			(layer "B.Fab")
		)
		(fp_line
			(start -0.120396 0.2794)
			(end 0.12065 0.2794)
			(stroke
				(width 0.1)
				(type default)
			)
			(layer "B.Fab")
		)
		(fp_line
			(start -0.12065 -0.2794)
			(end -0.12065 -0.3048)
			(stroke
				(width 0.1)
				(type default)
			)
			(layer "B.Fab")
		)
		(fp_line
			(start -0.12065 -0.3048)
			(end -0.67945 -0.3048)
			(stroke
				(width 0.1)
				(type default)
			)
			(layer "B.Fab")
		)
		(fp_line
			(start -0.67945 0.3048)
			(end -0.120396 0.3048)
			(stroke
				(width 0.1)
				(type default)
			)
			(layer "B.Fab")
		)
		(fp_line
			(start -0.67945 -0.3048)
			(end -0.67945 0.3048)
			(stroke
				(width 0.1)
				(type default)
			)
			(layer "B.Fab")
		)
		(pad "1" smd circle
			(at 0.40005 0)
			(size 0 0)
			(layers "B.Cu" "B.Mask" "B.Paste")
			(net "I3C_SPD_DDRGL_CPU0_SDA")
		)
		(pad "2" smd circle
			(at -0.40005 0)
			(size 0 0)
			(layers "B.Cu" "B.Mask" "B.Paste")
			(net "I3C_SPD_DDRG_CPU0_SDA")
		)
	)
	(footprint ""
		(layer "B.Cu")
		(at 118.091204 -390.560052 90)
		(property "Reference" "C490"
			(at 0 0 90)
			(layer "B.SilkS")
			(hide yes)
			(effects
				(font
					(size 1.27 1.27)
				)
				(justify mirror)
			)
		)
		(property "Value" ""
			(at 0 0 90)
			(layer "B.Fab")
			(effects
				(font
					(size 1.27 1.27)
				)
				(justify mirror)
			)
		)
		(duplicate_pad_numbers_are_jumpers no)
		(fp_line
			(start 0.7874 -0.4064)
			(end -0.7874 -0.4064)
			(stroke
				(width 0.1524)
				(type default)
			)
			(layer "B.SilkS")
		)
		(fp_line
			(start -0.7874 -0.4064)
			(end -0.7874 0.4064)
			(stroke
				(width 0.1524)
				(type default)
			)
			(layer "B.SilkS")
		)
		(fp_line
			(start 0.7874 0.4064)
			(end 0.7874 -0.4064)
			(stroke
				(width 0.1524)
				(type default)
			)
			(layer "B.SilkS")
		)
		(fp_line
			(start -0.7874 0.4064)
			(end 0.7874 0.4064)
			(stroke
				(width 0.1524)
				(type default)
			)
			(layer "B.SilkS")
		)
		(fp_line
			(start 0.67945 -0.305054)
			(end 0.12065 -0.305054)
			(stroke
				(width 0.1)
				(type default)
			)
			(layer "B.Fab")
		)
		(fp_line
			(start 0.12065 -0.305054)
			(end 0.12065 -0.2794)
			(stroke
				(width 0.1)
				(type default)
			)
			(layer "B.Fab")
		)
		(fp_line
			(start -0.12065 -0.3048)
			(end -0.67945 -0.3048)
			(stroke
				(width 0.1)
				(type default)
			)
			(layer "B.Fab")
		)
		(fp_line
			(start -0.67945 -0.3048)
			(end -0.67945 0.3048)
			(stroke
				(width 0.1)
				(type default)
			)
			(layer "B.Fab")
		)
		(fp_line
			(start 0.12065 -0.2794)
			(end -0.12065 -0.2794)
			(stroke
				(width 0.1)
				(type default)
			)
			(layer "B.Fab")
		)
		(fp_line
			(start -0.12065 -0.2794)
			(end -0.12065 -0.3048)
			(stroke
				(width 0.1)
				(type default)
			)
			(layer "B.Fab")
		)
		(fp_line
			(start 0.12065 0.2794)
			(end 0.12065 0.3048)
			(stroke
				(width 0.1)
				(type default)
			)
			(layer "B.Fab")
		)
		(fp_line
			(start -0.120396 0.2794)
			(end 0.12065 0.2794)
			(stroke
				(width 0.1)
				(type default)
			)
			(layer "B.Fab")
		)
		(fp_line
			(start 0.67945 0.3048)
			(end 0.67945 -0.305054)
			(stroke
				(width 0.1)
				(type default)
			)
			(layer "B.Fab")
		)
		(fp_line
			(start 0.12065 0.3048)
			(end 0.67945 0.3048)
			(stroke
				(width 0.1)
				(type default)
			)
			(layer "B.Fab")
		)
		(fp_line
			(start -0.120396 0.3048)
			(end -0.120396 0.2794)
			(stroke
				(width 0.1)
				(type default)
			)
			(layer "B.Fab")
		)
		(fp_line
			(start -0.67945 0.3048)
			(end -0.120396 0.3048)
			(stroke
				(width 0.1)
				(type default)
			)
			(layer "B.Fab")
		)
		(pad "1" smd circle
			(at 0.40005 0 270)
			(size 0 0)
			(layers "B.Cu" "B.Mask" "B.Paste")
			(net "P0V9_CPU1_RT3_2A")
		)
		(pad "2" smd circle
			(at -0.40005 0 270)
			(size 0 0)
			(layers "B.Cu" "B.Mask" "B.Paste")
			(net "GND")
		)
	)
)
